(kicad_pcb
	(version 20260206)
	(generator "pcbnew")
	(generator_version "10.0")
	(general
		(thickness 1.6)
		(legacy_teardrops no)
	)
	(paper "A4")
	(title_block
		(title "03242023_DA0F0TMBIJ0_F0T_Motherboard_J_brd_V01_OCP.brd")
		(comment 1 "Grand Teton / footprints 4330-4335 of 6105")
	)
	(layers
		(0 "F.Cu" signal "TOP")
		(4 "In1.Cu" signal "GND")
		(6 "In2.Cu" signal "IN1")
		(8 "In3.Cu" signal "GND1")
		(10 "In4.Cu" signal "IN2")
		(12 "In5.Cu" signal "GND2")
		(14 "In6.Cu" signal "IN3")
		(16 "In7.Cu" signal "GND3")
		(18 "In8.Cu" signal "VCC")
		(20 "In9.Cu" signal "VCC1")
		(22 "In10.Cu" signal "GND4")
		(24 "In11.Cu" signal "IN4")
		(26 "In12.Cu" signal "GND5")
		(28 "In13.Cu" signal "IN5")
		(30 "In14.Cu" signal "GND6")
		(32 "In15.Cu" signal "IN6")
		(34 "In16.Cu" signal "GND7")
		(2 "B.Cu" signal "BOTTOM")
		(9 "F.Adhes" user "F.Adhesive")
		(11 "B.Adhes" user "B.Adhesive")
		(13 "F.Paste" user "Package Geometry/Pastemask Top")
		(15 "B.Paste" user "Package Geometry/Pastemask Bottom")
		(5 "F.SilkS" user "Ref Des/Silkscreen Top")
		(7 "B.SilkS" user "Ref Des/Silkscreen Bottom")
		(1 "F.Mask" user "Board Geometry/Soldermask Top")
		(3 "B.Mask" user "Board Geometry/Soldermask Bottom")
		(17 "Dwgs.User" user "User.Drawings")
		(19 "Cmts.User" user "User.Comments")
		(21 "Eco1.User" user "User.Eco1")
		(23 "Eco2.User" user "User.Eco2")
		(25 "Edge.Cuts" user "Board Geometry/Outline")
		(27 "Margin" user)
		(31 "F.CrtYd" user "Package Geometry/Place Bound Top")
		(29 "B.CrtYd" user "Package Geometry/Place Bound Bottom")
		(35 "F.Fab" user "Ref Des/Assembly Top")
		(33 "B.Fab" user "Ref Des/Assembly Bottom")
	)
	(footprint ""
		(layer "B.Cu")
		(at 32.027368 -162.596322 -90)
		(property "Reference" "PR217"
			(at 0 0 90)
			(layer "B.SilkS")
			(hide yes)
			(effects
				(font
					(size 1.27 1.27)
				)
				(justify mirror)
			)
		)
		(property "Value" ""
			(at 0 0 90)
			(layer "B.Fab")
			(effects
				(font
					(size 1.27 1.27)
				)
				(justify mirror)
			)
		)
		(duplicate_pad_numbers_are_jumpers no)
		(fp_line
			(start -0.7874 0.4064)
			(end 0.7874 0.4064)
			(stroke
				(width 0.1524)
				(type default)
			)
			(layer "B.SilkS")
		)
		(fp_line
			(start 0.7874 0.4064)
			(end 0.7874 -0.4064)
			(stroke
				(width 0.1524)
				(type default)
			)
			(layer "B.SilkS")
		)
		(fp_line
			(start -0.7874 -0.4064)
			(end -0.7874 0.4064)
			(stroke
				(width 0.1524)
				(type default)
			)
			(layer "B.SilkS")
		)
		(fp_line
			(start 0.7874 -0.4064)
			(end -0.7874 -0.4064)
			(stroke
				(width 0.1524)
				(type default)
			)
			(layer "B.SilkS")
		)
		(fp_line
			(start -0.67945 0.3048)
			(end -0.120396 0.3048)
			(stroke
				(width 0.1)
				(type default)
			)
			(layer "B.Fab")
		)
		(fp_line
			(start -0.120396 0.3048)
			(end -0.120396 0.2794)
			(stroke
				(width 0.1)
				(type default)
			)
			(layer "B.Fab")
		)
		(fp_line
			(start 0.12065 0.3048)
			(end 0.67945 0.3048)
			(stroke
				(width 0.1)
				(type default)
			)
			(layer "B.Fab")
		)
		(fp_line
			(start 0.67945 0.3048)
			(end 0.67945 -0.305054)
			(stroke
				(width 0.1)
				(type default)
			)
			(layer "B.Fab")
		)
		(fp_line
			(start -0.120396 0.2794)
			(end 0.12065 0.2794)
			(stroke
				(width 0.1)
				(type default)
			)
			(layer "B.Fab")
		)
		(fp_line
			(start 0.12065 0.2794)
			(end 0.12065 0.3048)
			(stroke
				(width 0.1)
				(type default)
			)
			(layer "B.Fab")
		)
		(fp_line
			(start -0.12065 -0.2794)
			(end -0.12065 -0.3048)
			(stroke
				(width 0.1)
				(type default)
			)
			(layer "B.Fab")
		)
		(fp_line
			(start 0.12065 -0.2794)
			(end -0.12065 -0.2794)
			(stroke
				(width 0.1)
				(type default)
			)
			(layer "B.Fab")
		)
		(fp_line
			(start -0.67945 -0.3048)
			(end -0.67945 0.3048)
			(stroke
				(width 0.1)
				(type default)
			)
			(layer "B.Fab")
		)
		(fp_line
			(start -0.12065 -0.3048)
			(end -0.67945 -0.3048)
			(stroke
				(width 0.1)
				(type default)
			)
			(layer "B.Fab")
		)
		(fp_line
			(start 0.12065 -0.305054)
			(end 0.12065 -0.2794)
			(stroke
				(width 0.1)
				(type default)
			)
			(layer "B.Fab")
		)
		(fp_line
			(start 0.67945 -0.305054)
			(end 0.12065 -0.305054)
			(stroke
				(width 0.1)
				(type default)
			)
			(layer "B.Fab")
		)
		(pad "1" smd circle
			(at 0.40005 0 90)
			(size 0 0)
			(layers "B.Cu" "B.Mask" "B.Paste")
			(net "P3V3_AUX")
		)
		(pad "2" smd circle
			(at -0.40005 0 90)
			(size 0 0)
			(layers "B.Cu" "B.Mask" "B.Paste")
			(net "PVCCD_HV_CPU1_FAULT")
		)
	)
	(footprint ""
		(layer "B.Cu")
		(at 18.838926 -97.330768 -90)
		(property "Reference" "R3655"
			(at 0 0 90)
			(layer "B.SilkS")
			(hide yes)
			(effects
				(font
					(size 1.27 1.27)
				)
				(justify mirror)
			)
		)
		(property "Value" ""
			(at 0 0 90)
			(layer "B.Fab")
			(effects
				(font
					(size 1.27 1.27)
				)
				(justify mirror)
			)
		)
		(duplicate_pad_numbers_are_jumpers no)
		(fp_line
			(start -0.7874 0.4064)
			(end 0.7874 0.4064)
			(stroke
				(width 0.1524)
				(type default)
			)
			(layer "B.SilkS")
		)
		(fp_line
			(start 0.7874 0.4064)
			(end 0.7874 -0.4064)
			(stroke
				(width 0.1524)
				(type default)
			)
			(layer "B.SilkS")
		)
		(fp_line
			(start -0.7874 -0.4064)
			(end -0.7874 0.4064)
			(stroke
				(width 0.1524)
				(type default)
			)
			(layer "B.SilkS")
		)
		(fp_line
			(start 0.7874 -0.4064)
			(end -0.7874 -0.4064)
			(stroke
				(width 0.1524)
				(type default)
			)
			(layer "B.SilkS")
		)
		(fp_line
			(start -0.67945 0.3048)
			(end -0.120396 0.3048)
			(stroke
				(width 0.1)
				(type default)
			)
			(layer "B.Fab")
		)
		(fp_line
			(start -0.120396 0.3048)
			(end -0.120396 0.2794)
			(stroke
				(width 0.1)
				(type default)
			)
			(layer "B.Fab")
		)
		(fp_line
			(start 0.12065 0.3048)
			(end 0.67945 0.3048)
			(stroke
				(width 0.1)
				(type default)
			)
			(layer "B.Fab")
		)
		(fp_line
			(start 0.67945 0.3048)
			(end 0.67945 -0.305054)
			(stroke
				(width 0.1)
				(type default)
			)
			(layer "B.Fab")
		)
		(fp_line
			(start -0.120396 0.2794)
			(end 0.12065 0.2794)
			(stroke
				(width 0.1)
				(type default)
			)
			(layer "B.Fab")
		)
		(fp_line
			(start 0.12065 0.2794)
			(end 0.12065 0.3048)
			(stroke
				(width 0.1)
				(type default)
			)
			(layer "B.Fab")
		)
		(fp_line
			(start -0.12065 -0.2794)
			(end -0.12065 -0.3048)
			(stroke
				(width 0.1)
				(type default)
			)
			(layer "B.Fab")
		)
		(fp_line
			(start 0.12065 -0.2794)
			(end -0.12065 -0.2794)
			(stroke
				(width 0.1)
				(type default)
			)
			(layer "B.Fab")
		)
		(fp_line
			(start -0.67945 -0.3048)
			(end -0.67945 0.3048)
			(stroke
				(width 0.1)
				(type default)
			)
			(layer "B.Fab")
		)
		(fp_line
			(start -0.12065 -0.3048)
			(end -0.67945 -0.3048)
			(stroke
				(width 0.1)
				(type default)
			)
			(layer "B.Fab")
		)
		(fp_line
			(start 0.12065 -0.305054)
			(end 0.12065 -0.2794)
			(stroke
				(width 0.1)
				(type default)
			)
			(layer "B.Fab")
		)
		(fp_line
			(start 0.67945 -0.305054)
			(end 0.12065 -0.305054)
			(stroke
				(width 0.1)
				(type default)
			)
			(layer "B.Fab")
		)
		(pad "1" smd circle
			(at 0.40005 0 90)
			(size 0 0)
			(layers "B.Cu" "B.Mask" "B.Paste")
			(net "P3V3_AUX")
		)
		(pad "2" smd circle
			(at -0.40005 0 90)
			(size 0 0)
			(layers "B.Cu" "B.Mask" "B.Paste")
			(net "P3V3_AUX_USB_HUB")
		)
	)
	(footprint ""
		(layer "B.Cu")
		(at 61.52388 -8.981948 90)
		(property "Reference" "C1836"
			(at 0 0 90)
			(layer "B.SilkS")
			(hide yes)
			(effects
				(font
					(size 1.27 1.27)
				)
				(justify mirror)
			)
		)
		(property "Value" ""
			(at 0 0 90)
			(layer "B.Fab")
			(effects
				(font
					(size 1.27 1.27)
				)
				(justify mirror)
			)
		)
		(duplicate_pad_numbers_are_jumpers no)
		(fp_line
			(start 0.7874 -0.4064)
			(end -0.7874 -0.4064)
			(stroke
				(width 0.1524)
				(type default)
			)
			(layer "B.SilkS")
		)
		(fp_line
			(start -0.7874 -0.4064)
			(end -0.7874 0.4064)
			(stroke
				(width 0.1524)
				(type default)
			)
			(layer "B.SilkS")
		)
		(fp_line
			(start 0.7874 0.4064)
			(end 0.7874 -0.4064)
			(stroke
				(width 0.1524)
				(type default)
			)
			(layer "B.SilkS")
		)
		(fp_line
			(start -0.7874 0.4064)
			(end 0.7874 0.4064)
			(stroke
				(width 0.1524)
				(type default)
			)
			(layer "B.SilkS")
		)
		(fp_line
			(start 0.67945 -0.305054)
			(end 0.12065 -0.305054)
			(stroke
				(width 0.1)
				(type default)
			)
			(layer "B.Fab")
		)
		(fp_line
			(start 0.12065 -0.305054)
			(end 0.12065 -0.2794)
			(stroke
				(width 0.1)
				(type default)
			)
			(layer "B.Fab")
		)
		(fp_line
			(start -0.12065 -0.3048)
			(end -0.67945 -0.3048)
			(stroke
				(width 0.1)
				(type default)
			)
			(layer "B.Fab")
		)
		(fp_line
			(start -0.67945 -0.3048)
			(end -0.67945 0.3048)
			(stroke
				(width 0.1)
				(type default)
			)
			(layer "B.Fab")
		)
		(fp_line
			(start 0.12065 -0.2794)
			(end -0.12065 -0.2794)
			(stroke
				(width 0.1)
				(type default)
			)
			(layer "B.Fab")
		)
		(fp_line
			(start -0.12065 -0.2794)
			(end -0.12065 -0.3048)
			(stroke
				(width 0.1)
				(type default)
			)
			(layer "B.Fab")
		)
		(fp_line
			(start 0.12065 0.2794)
			(end 0.12065 0.3048)
			(stroke
				(width 0.1)
				(type default)
			)
			(layer "B.Fab")
		)
		(fp_line
			(start -0.120396 0.2794)
			(end 0.12065 0.2794)
			(stroke
				(width 0.1)
				(type default)
			)
			(layer "B.Fab")
		)
		(fp_line
			(start 0.67945 0.3048)
			(end 0.67945 -0.305054)
			(stroke
				(width 0.1)
				(type default)
			)
			(layer "B.Fab")
		)
		(fp_line
			(start 0.12065 0.3048)
			(end 0.67945 0.3048)
			(stroke
				(width 0.1)
				(type default)
			)
			(layer "B.Fab")
		)
		(fp_line
			(start -0.120396 0.3048)
			(end -0.120396 0.2794)
			(stroke
				(width 0.1)
				(type default)
			)
			(layer "B.Fab")
		)
		(fp_line
			(start -0.67945 0.3048)
			(end -0.120396 0.3048)
			(stroke
				(width 0.1)
				(type default)
			)
			(layer "B.Fab")
		)
		(pad "1" smd circle
			(at 0.40005 0 270)
			(size 0 0)
			(layers "B.Cu" "B.Mask" "B.Paste")
			(net "P3V3_OCP_V3_2")
		)
		(pad "2" smd circle
			(at -0.40005 0 270)
			(size 0 0)
			(layers "B.Cu" "B.Mask" "B.Paste")
			(net "GND")
		)
	)
	(footprint ""
		(layer "B.Cu")
		(at 450.482716 -10.594086 90)
		(property "Reference" "R422"
			(at 0 0 90)
			(layer "B.SilkS")
			(hide yes)
			(effects
				(font
					(size 1.27 1.27)
				)
				(justify mirror)
			)
		)
		(property "Value" ""
			(at 0 0 90)
			(layer "B.Fab")
			(effects
				(font
					(size 1.27 1.27)
				)
				(justify mirror)
			)
		)
		(duplicate_pad_numbers_are_jumpers no)
		(fp_line
			(start 0.7874 -0.4064)
			(end -0.7874 -0.4064)
			(stroke
				(width 0.1524)
				(type default)
			)
			(layer "B.SilkS")
		)
		(fp_line
			(start -0.7874 -0.4064)
			(end -0.7874 0.4064)
			(stroke
				(width 0.1524)
				(type default)
			)
			(layer "B.SilkS")
		)
		(fp_line
			(start 0.7874 0.4064)
			(end 0.7874 -0.4064)
			(stroke
				(width 0.1524)
				(type default)
			)
			(layer "B.SilkS")
		)
		(fp_line
			(start -0.7874 0.4064)
			(end 0.7874 0.4064)
			(stroke
				(width 0.1524)
				(type default)
			)
			(layer "B.SilkS")
		)
		(fp_line
			(start 0.67945 -0.305054)
			(end 0.12065 -0.305054)
			(stroke
				(width 0.1)
				(type default)
			)
			(layer "B.Fab")
		)
		(fp_line
			(start 0.12065 -0.305054)
			(end 0.12065 -0.2794)
			(stroke
				(width 0.1)
				(type default)
			)
			(layer "B.Fab")
		)
		(fp_line
			(start -0.12065 -0.3048)
			(end -0.67945 -0.3048)
			(stroke
				(width 0.1)
				(type default)
			)
			(layer "B.Fab")
		)
		(fp_line
			(start -0.67945 -0.3048)
			(end -0.67945 0.3048)
			(stroke
				(width 0.1)
				(type default)
			)
			(layer "B.Fab")
		)
		(fp_line
			(start 0.12065 -0.2794)
			(end -0.12065 -0.2794)
			(stroke
				(width 0.1)
				(type default)
			)
			(layer "B.Fab")
		)
		(fp_line
			(start -0.12065 -0.2794)
			(end -0.12065 -0.3048)
			(stroke
				(width 0.1)
				(type default)
			)
			(layer "B.Fab")
		)
		(fp_line
			(start 0.12065 0.2794)
			(end 0.12065 0.3048)
			(stroke
				(width 0.1)
				(type default)
			)
			(layer "B.Fab")
		)
		(fp_line
			(start -0.120396 0.2794)
			(end 0.12065 0.2794)
			(stroke
				(width 0.1)
				(type default)
			)
			(layer "B.Fab")
		)
		(fp_line
			(start 0.67945 0.3048)
			(end 0.67945 -0.305054)
			(stroke
				(width 0.1)
				(type default)
			)
			(layer "B.Fab")
		)
		(fp_line
			(start 0.12065 0.3048)
			(end 0.67945 0.3048)
			(stroke
				(width 0.1)
				(type default)
			)
			(layer "B.Fab")
		)
		(fp_line
			(start -0.120396 0.3048)
			(end -0.120396 0.2794)
			(stroke
				(width 0.1)
				(type default)
			)
			(layer "B.Fab")
		)
		(fp_line
			(start -0.67945 0.3048)
			(end -0.120396 0.3048)
			(stroke
				(width 0.1)
				(type default)
			)
			(layer "B.Fab")
		)
		(pad "1" smd circle
			(at 0.40005 0 270)
			(size 0 0)
			(layers "B.Cu" "B.Mask" "B.Paste")
			(net "SGPIO_OCP_SFF_DATAOUT")
		)
		(pad "2" smd circle
			(at -0.40005 0 270)
			(size 0 0)
			(layers "B.Cu" "B.Mask" "B.Paste")
			(net "GND")
		)
	)
	(footprint ""
		(layer "B.Cu")
		(at 297.45813 -403.031452 90)
		(property "Reference" "PR2515"
			(at 0 0 90)
			(layer "B.SilkS")
			(hide yes)
			(effects
				(font
					(size 1.27 1.27)
				)
				(justify mirror)
			)
		)
		(property "Value" ""
			(at 0 0 90)
			(layer "B.Fab")
			(effects
				(font
					(size 1.27 1.27)
				)
				(justify mirror)
			)
		)
		(duplicate_pad_numbers_are_jumpers no)
		(fp_line
			(start 0.7874 -0.4064)
			(end -0.7874 -0.4064)
			(stroke
				(width 0.1524)
				(type default)
			)
			(layer "B.SilkS")
		)
		(fp_line
			(start -0.7874 -0.4064)
			(end -0.7874 0.4064)
			(stroke
				(width 0.1524)
				(type default)
			)
			(layer "B.SilkS")
		)
		(fp_line
			(start 0.7874 0.4064)
			(end 0.7874 -0.4064)
			(stroke
				(width 0.1524)
				(type default)
			)
			(layer "B.SilkS")
		)
		(fp_line
			(start -0.7874 0.4064)
			(end 0.7874 0.4064)
			(stroke
				(width 0.1524)
				(type default)
			)
			(layer "B.SilkS")
		)
		(fp_line
			(start 0.67945 -0.305054)
			(end 0.12065 -0.305054)
			(stroke
				(width 0.1)
				(type default)
			)
			(layer "B.Fab")
		)
		(fp_line
			(start 0.12065 -0.305054)
			(end 0.12065 -0.2794)
			(stroke
				(width 0.1)
				(type default)
			)
			(layer "B.Fab")
		)
		(fp_line
			(start -0.12065 -0.3048)
			(end -0.67945 -0.3048)
			(stroke
				(width 0.1)
				(type default)
			)
			(layer "B.Fab")
		)
		(fp_line
			(start -0.67945 -0.3048)
			(end -0.67945 0.3048)
			(stroke
				(width 0.1)
				(type default)
			)
			(layer "B.Fab")
		)
		(fp_line
			(start 0.12065 -0.2794)
			(end -0.12065 -0.2794)
			(stroke
				(width 0.1)
				(type default)
			)
			(layer "B.Fab")
		)
		(fp_line
			(start -0.12065 -0.2794)
			(end -0.12065 -0.3048)
			(stroke
				(width 0.1)
				(type default)
			)
			(layer "B.Fab")
		)
		(fp_line
			(start 0.12065 0.2794)
			(end 0.12065 0.3048)
			(stroke
				(width 0.1)
				(type default)
			)
			(layer "B.Fab")
		)
		(fp_line
			(start -0.120396 0.2794)
			(end 0.12065 0.2794)
			(stroke
				(width 0.1)
				(type default)
			)
			(layer "B.Fab")
		)
		(fp_line
			(start 0.67945 0.3048)
			(end 0.67945 -0.305054)
			(stroke
				(width 0.1)
				(type default)
			)
			(layer "B.Fab")
		)
		(fp_line
			(start 0.12065 0.3048)
			(end 0.67945 0.3048)
			(stroke
				(width 0.1)
				(type default)
			)
			(layer "B.Fab")
		)
		(fp_line
			(start -0.120396 0.3048)
			(end -0.120396 0.2794)
			(stroke
				(width 0.1)
				(type default)
			)
			(layer "B.Fab")
		)
		(fp_line
			(start -0.67945 0.3048)
			(end -0.120396 0.3048)
			(stroke
				(width 0.1)
				(type default)
			)
			(layer "B.Fab")
		)
		(pad "1" smd circle
			(at 0.40005 0 270)
			(size 0 0)
			(layers "B.Cu" "B.Mask" "B.Paste")
			(net "P12V_HSC_ADC_N")
		)
		(pad "2" smd circle
			(at -0.40005 0 270)
			(size 0 0)
			(layers "B.Cu" "B.Mask" "B.Paste")
			(net "P12V_HSC_SENSE2_R1_N")
		)
	)
	(footprint ""
		(layer "B.Cu")
		(at 311.84088 -53.304948)
		(property "Reference" "R4106"
			(at 0 0 0)
			(layer "B.SilkS")
			(hide yes)
			(effects
				(font
					(size 1.27 1.27)
				)
				(justify mirror)
			)
		)
		(property "Value" ""
			(at 0 0 0)
			(layer "B.Fab")
			(effects
				(font
					(size 1.27 1.27)
				)
				(justify mirror)
			)
		)
		(duplicate_pad_numbers_are_jumpers no)
		(fp_line
			(start -0.7874 -0.4064)
			(end -0.7874 0.4064)
			(stroke
				(width 0.1524)
				(type default)
			)
			(layer "B.SilkS")
		)
		(fp_line
			(start -0.7874 0.4064)
			(end 0.7874 0.4064)
			(stroke
				(width 0.1524)
				(type default)
			)
			(layer "B.SilkS")
		)
		(fp_line
			(start 0.7874 -0.4064)
			(end -0.7874 -0.4064)
			(stroke
				(width 0.1524)
				(type default)
			)
			(layer "B.SilkS")
		)
		(fp_line
			(start 0.7874 0.4064)
			(end 0.7874 -0.4064)
			(stroke
				(width 0.1524)
				(type default)
			)
			(layer "B.SilkS")
		)
		(fp_line
			(start -0.67945 -0.3048)
			(end -0.67945 0.3048)
			(stroke
				(width 0.1)
				(type default)
			)
			(layer "B.Fab")
		)
		(fp_line
			(start -0.67945 0.3048)
			(end -0.120396 0.3048)
			(stroke
				(width 0.1)
				(type default)
			)
			(layer "B.Fab")
		)
		(fp_line
			(start -0.12065 -0.3048)
			(end -0.67945 -0.3048)
			(stroke
				(width 0.1)
				(type default)
			)
			(layer "B.Fab")
		)
		(fp_line
			(start -0.12065 -0.2794)
			(end -0.12065 -0.3048)
			(stroke
				(width 0.1)
				(type default)
			)
			(layer "B.Fab")
		)
		(fp_line
			(start -0.120396 0.2794)
			(end 0.12065 0.2794)
			(stroke
				(width 0.1)
				(type default)
			)
			(layer "B.Fab")
		)
		(fp_line
			(start -0.120396 0.3048)
			(end -0.120396 0.2794)
			(stroke
				(width 0.1)
				(type default)
			)
			(layer "B.Fab")
		)
		(fp_line
			(start 0.12065 -0.305054)
			(end 0.12065 -0.2794)
			(stroke
				(width 0.1)
				(type default)
			)
			(layer "B.Fab")
		)
		(fp_line
			(start 0.12065 -0.2794)
			(end -0.12065 -0.2794)
			(stroke
				(width 0.1)
				(type default)
			)
			(layer "B.Fab")
		)
		(fp_line
			(start 0.12065 0.2794)
			(end 0.12065 0.3048)
			(stroke
				(width 0.1)
				(type default)
			)
			(layer "B.Fab")
		)
		(fp_line
			(start 0.12065 0.3048)
			(end 0.67945 0.3048)
			(stroke
				(width 0.1)
				(type default)
			)
			(layer "B.Fab")
		)
		(fp_line
			(start 0.67945 -0.305054)
			(end 0.12065 -0.305054)
			(stroke
				(width 0.1)
				(type default)
			)
			(layer "B.Fab")
		)
		(fp_line
			(start 0.67945 0.3048)
			(end 0.67945 -0.305054)
			(stroke
				(width 0.1)
				(type default)
			)
			(layer "B.Fab")
		)
		(pad "1" smd circle
			(at 0.40005 0 180)
			(size 0 0)
			(layers "B.Cu" "B.Mask" "B.Paste")
			(net "PD_GPP_M_8")
		)
		(pad "2" smd circle
			(at -0.40005 0 180)
			(size 0 0)
			(layers "B.Cu" "B.Mask" "B.Paste")
			(net "GND")
		)
	)
)
